(kicad_pcb
	(version 20260206)
	(generator "pcbnew")
	(generator_version "10.0")
	(general
		(thickness 1.6)
		(legacy_teardrops no)
	)
	(paper "A4")
	(title_block
		(title "Bryce Canyon_F.DPB_16315-1-OCP.brd")
		(comment 1 "Bryce Canyon / footprints 641-646 of 2223")
	)
	(layers
		(0 "F.Cu" signal "TOP")
		(4 "In1.Cu" signal "L2GND")
		(6 "In2.Cu" signal "L3")
		(8 "In3.Cu" signal "L4GND")
		(10 "In4.Cu" signal "L5")
		(12 "In5.Cu" signal "L6VCC")
		(14 "In6.Cu" signal "L7VCC")
		(16 "In7.Cu" signal "L8")
		(18 "In8.Cu" signal "L9GND")
		(20 "In9.Cu" signal "L10")
		(22 "In10.Cu" signal "L11GND")
		(2 "B.Cu" signal "BOTTOM")
		(9 "F.Adhes" user "F.Adhesive")
		(11 "B.Adhes" user "B.Adhesive")
		(13 "F.Paste" user "Package Geometry/Pastemask Top")
		(15 "B.Paste" user "Package Geometry/Pastemask Bottom")
		(5 "F.SilkS" user "Ref Des/Silkscreen Top")
		(7 "B.SilkS" user "Ref Des/Silkscreen Bottom")
		(1 "F.Mask" user "Board Geometry/Soldermask Top")
		(3 "B.Mask" user "Board Geometry/Soldermask Bottom")
		(17 "Dwgs.User" user "User.Drawings")
		(19 "Cmts.User" user "User.Comments")
		(21 "Eco1.User" user "User.Eco1")
		(23 "Eco2.User" user "User.Eco2")
		(25 "Edge.Cuts" user "Board Geometry/Outline")
		(27 "Margin" user)
		(31 "F.CrtYd" user "Package Geometry/Place Bound Top")
		(29 "B.CrtYd" user "Package Geometry/Place Bound Bottom")
		(35 "F.Fab" user "Ref Des/Assembly Top")
		(33 "B.Fab" user "Ref Des/Assembly Bottom")
	)
	(footprint ""
		(layer "F.Cu")
		(at 314.94603 -293.906956)
		(property "Reference" "Q293"
			(at 0 0 0)
			(layer "F.SilkS")
			(hide yes)
			(effects
				(font
					(size 1.27 1.27)
				)
			)
		)
		(property "Value" "SSM3K324R-GP"
			(at 0.127 -8.9662 0)
			(unlocked yes)
			(layer "F.Fab")
			(hide yes)
			(effects
				(font
					(size 1.016 1.016)
					(thickness 0.1524)
				)
			)
		)
		(property "Device Type" "SOT23DGS2D4H35"
			(at 0.127 -10.4902 0)
			(unlocked yes)
			(layer "F.Fab")
			(hide yes)
			(effects
				(font
					(size 1.016 1.016)
					(thickness 0.1524)
				)
			)
		)
		(duplicate_pad_numbers_are_jumpers no)
		(fp_line
			(start -1.651 -1.778)
			(end -1.651 1.778)
			(stroke
				(width 0.1524)
				(type default)
			)
			(layer "F.SilkS")
		)
		(fp_line
			(start -1.651 1.778)
			(end 1.651 1.778)
			(stroke
				(width 0.1524)
				(type default)
			)
			(layer "F.SilkS")
		)
		(fp_line
			(start 1.651 -1.778)
			(end -1.651 -1.778)
			(stroke
				(width 0.1524)
				(type default)
			)
			(layer "F.SilkS")
		)
		(fp_line
			(start 1.651 1.778)
			(end 1.651 -1.778)
			(stroke
				(width 0.1524)
				(type default)
			)
			(layer "F.SilkS")
		)
		(fp_poly
			(pts
				(xy -1.778 1.8796) (xy -1.778 -1.8796) (xy 1.778 -1.8796) (xy 1.778 1.8796)
			)
			(stroke
				(width 0)
				(type default)
			)
			(fill no)
			(layer "F.CrtYd")
		)
		(fp_poly
			(pts
				(xy -1.778 1.8796) (xy -1.778 -1.8796) (xy 1.778 -1.8796) (xy 1.778 1.8796)
			)
			(stroke
				(width 0)
				(type default)
			)
			(fill no)
			(layer "F.Fab")
		)
		(pad "D" smd custom
			(at 0 -0.9525)
			(size 0.1905 0.1905)
			(layers "F.Cu" "F.Mask" "F.Paste")
			(net "DRV_ACT_30_N")
			(options
				(clearance outline)
				(anchor circle)
			)
			(primitives
				(gr_poly
					(pts
						(arc
							(start -0.1778 0.5715)
							(mid -0.321484 0.511984)
							(end -0.381 0.3683)
						)
						(arc
							(start -0.381 -0.3683)
							(mid -0.321484 -0.511984)
							(end -0.1778 -0.5715)
						)
						(arc
							(start 0.1778 -0.5715)
							(mid 0.321484 -0.511984)
							(end 0.381 -0.3683)
						)
						(arc
							(start 0.381 0.3683)
							(mid 0.321484 0.511984)
							(end 0.1778 0.5715)
						)
					)
					(width 0)
					(fill yes)
				)
			)
		)
		(pad "G" smd custom
			(at -0.98425 0.9525)
			(size 0.1905 0.1905)
			(layers "F.Cu" "F.Mask" "F.Paste")
			(net "DRIVE_B_30_ACT")
			(options
				(clearance outline)
				(anchor circle)
			)
			(primitives
				(gr_poly
					(pts
						(arc
							(start -0.1778 0.5715)
							(mid -0.321484 0.511984)
							(end -0.381 0.3683)
						)
						(arc
							(start -0.381 -0.3683)
							(mid -0.321484 -0.511984)
							(end -0.1778 -0.5715)
						)
						(arc
							(start 0.1778 -0.5715)
							(mid 0.321484 -0.511984)
							(end 0.381 -0.3683)
						)
						(arc
							(start 0.381 0.3683)
							(mid 0.321484 0.511984)
							(end 0.1778 0.5715)
						)
					)
					(width 0)
					(fill yes)
				)
			)
		)
		(pad "S" smd custom
			(at 0.98425 0.9525)
			(size 0.1905 0.1905)
			(layers "F.Cu" "F.Mask" "F.Paste")
			(net "GND")
			(options
				(clearance outline)
				(anchor circle)
			)
			(primitives
				(gr_poly
					(pts
						(arc
							(start -0.1778 0.5715)
							(mid -0.321484 0.511984)
							(end -0.381 0.3683)
						)
						(arc
							(start -0.381 -0.3683)
							(mid -0.321484 -0.511984)
							(end -0.1778 -0.5715)
						)
						(arc
							(start 0.1778 -0.5715)
							(mid 0.321484 -0.511984)
							(end 0.381 -0.3683)
						)
						(arc
							(start 0.381 0.3683)
							(mid 0.321484 0.511984)
							(end 0.1778 0.5715)
						)
					)
					(width 0)
					(fill yes)
				)
			)
		)
	)
	(footprint ""
		(layer "F.Cu")
		(at 256.2098 -290.195 180)
		(property "Reference" "R7"
			(at 0 0 180)
			(layer "F.SilkS")
			(hide yes)
			(effects
				(font
					(size 1.27 1.27)
				)
			)
		)
		(property "Value" "4K7R2F-GP"
			(at 0.064008 -3.993896 180)
			(unlocked yes)
			(layer "F.Fab")
			(hide yes)
			(effects
				(font
					(size 1.016 1.016)
					(thickness 0.1524)
				)
			)
		)
		(property "Device Type" "R402H16"
			(at 0.064008 -5.517896 180)
			(unlocked yes)
			(layer "F.Fab")
			(hide yes)
			(effects
				(font
					(size 1.016 1.016)
					(thickness 0.1524)
				)
			)
		)
		(duplicate_pad_numbers_are_jumpers no)
		(fp_line
			(start 0.508 -0.9398)
			(end -0.508 -0.9398)
			(stroke
				(width 0.1524)
				(type default)
			)
			(layer "F.SilkS")
		)
		(fp_line
			(start -0.508 -0.9398)
			(end -0.508 0.9398)
			(stroke
				(width 0.1524)
				(type default)
			)
			(layer "F.SilkS")
		)
		(fp_rect
			(start -0.508 0.9398)
			(end 0.508 -0.9398)
			(stroke
				(width 0)
				(type default)
			)
			(fill no)
			(layer "F.CrtYd")
		)
		(fp_rect
			(start -0.508 0.9398)
			(end 0.508 -0.9398)
			(stroke
				(width 0)
				(type default)
			)
			(fill no)
			(layer "F.Fab")
		)
		(pad "1" smd custom
			(at 0 -0.4445 180)
			(size 0.1397 0.1397)
			(layers "F.Cu" "F.Mask" "F.Paste")
			(net "P3V3_STBY_A")
			(options
				(clearance outline)
				(anchor circle)
			)
			(primitives
				(gr_poly
					(pts
						(arc
							(start -0.1778 -0.2794)
							(mid -0.249642 -0.249642)
							(end -0.2794 -0.1778)
						)
						(arc
							(start -0.2794 0.1778)
							(mid -0.249642 0.249642)
							(end -0.1778 0.2794)
						)
						(arc
							(start 0.1778 0.2794)
							(mid 0.249642 0.249642)
							(end 0.2794 0.1778)
						)
						(arc
							(start 0.2794 -0.1778)
							(mid 0.249642 -0.249642)
							(end 0.1778 -0.2794)
						)
					)
					(width 0)
					(fill yes)
				)
			)
		)
		(pad "2" smd custom
			(at 0 0.4445 180)
			(size 0.1397 0.1397)
			(layers "F.Cu" "F.Mask" "F.Paste")
			(net "EEPROM_A1")
			(options
				(clearance outline)
				(anchor circle)
			)
			(primitives
				(gr_poly
					(pts
						(arc
							(start -0.1778 -0.2794)
							(mid -0.249642 -0.249642)
							(end -0.2794 -0.1778)
						)
						(arc
							(start -0.2794 0.1778)
							(mid -0.249642 0.249642)
							(end -0.1778 0.2794)
						)
						(arc
							(start 0.1778 0.2794)
							(mid 0.249642 0.249642)
							(end 0.2794 0.1778)
						)
						(arc
							(start 0.2794 -0.1778)
							(mid 0.249642 -0.249642)
							(end 0.1778 -0.2794)
						)
					)
					(width 0)
					(fill yes)
				)
			)
		)
	)
	(footprint ""
		(layer "F.Cu")
		(at 427.009052 -65.826894 180)
		(property "Reference" "C470"
			(at 0 0 180)
			(layer "F.SilkS")
			(hide yes)
			(effects
				(font
					(size 1.27 1.27)
				)
			)
		)
		(property "Value" "SC10U16V6KX-2GP"
			(at -0.0762 -5.1308 180)
			(unlocked yes)
			(layer "F.Fab")
			(hide yes)
			(effects
				(font
					(size 1.016 1.016)
					(thickness 0.1524)
				)
			)
		)
		(property "Device Type" "C1206H71"
			(at -0.127 -6.6548 180)
			(unlocked yes)
			(layer "F.Fab")
			(hide yes)
			(effects
				(font
					(size 1.016 1.016)
					(thickness 0.1524)
				)
			)
		)
		(duplicate_pad_numbers_are_jumpers no)
		(fp_line
			(start 1.016 2.2352)
			(end -1.016 2.2352)
			(stroke
				(width 0.1524)
				(type default)
			)
			(layer "F.SilkS")
		)
		(fp_line
			(start 1.016 0.8382)
			(end 1.016 2.2352)
			(stroke
				(width 0.1524)
				(type default)
			)
			(layer "F.SilkS")
		)
		(fp_line
			(start 1.016 -2.2352)
			(end 1.016 -0.8382)
			(stroke
				(width 0.1524)
				(type default)
			)
			(layer "F.SilkS")
		)
		(fp_line
			(start -1.016 2.2352)
			(end -1.016 0.8382)
			(stroke
				(width 0.1524)
				(type default)
			)
			(layer "F.SilkS")
		)
		(fp_line
			(start -1.016 -0.8382)
			(end -1.016 -2.2352)
			(stroke
				(width 0.1524)
				(type default)
			)
			(layer "F.SilkS")
		)
		(fp_line
			(start -1.016 -2.2352)
			(end 1.016 -2.2352)
			(stroke
				(width 0.1524)
				(type default)
			)
			(layer "F.SilkS")
		)
		(fp_rect
			(start -1.0922 2.3114)
			(end 1.0922 -2.3114)
			(stroke
				(width 0)
				(type default)
			)
			(fill no)
			(layer "F.CrtYd")
		)
		(fp_poly
			(pts
				(xy 1.0922 -2.3114) (xy 1.0922 2.3114) (xy -1.0922 2.3114) (xy -1.0922 -2.3114)
			)
			(stroke
				(width 0)
				(type default)
			)
			(fill no)
			(layer "F.Fab")
		)
		(pad "1" smd rect
			(at 0 -1.397 180)
			(size 1.651 1.27)
			(layers "F.Cu" "F.Mask" "F.Paste")
			(net "P5V_HDD33")
		)
		(pad "2" smd rect
			(at 0 1.397 180)
			(size 1.651 1.27)
			(layers "F.Cu" "F.Mask" "F.Paste")
			(net "GND")
		)
	)
	(footprint ""
		(layer "F.Cu")
		(at 475.784926 -55.285894 180)
		(property "Reference" "Q209"
			(at 0 0 180)
			(layer "F.SilkS")
			(hide yes)
			(effects
				(font
					(size 1.27 1.27)
				)
			)
		)
		(property "Value" "AO4406AL-GP"
			(at -3.707384 -1.5367 180)
			(unlocked yes)
			(layer "F.Fab")
			(hide yes)
			(effects
				(font
					(size 1.016 1.016)
					(thickness 0.1524)
				)
			)
		)
		(property "Device Type" "SOIC8H69"
			(at -3.707384 -3.0607 180)
			(unlocked yes)
			(layer "F.Fab")
			(hide yes)
			(effects
				(font
					(size 1.016 1.016)
					(thickness 0.1524)
				)
			)
		)
		(duplicate_pad_numbers_are_jumpers no)
		(fp_line
			(start 2.1336 1.4224)
			(end 2.1336 -1.4224)
			(stroke
				(width 0.1524)
				(type default)
			)
			(layer "F.SilkS")
		)
		(fp_line
			(start 2.1336 -1.4224)
			(end -2.7432 -1.4224)
			(stroke
				(width 0.1524)
				(type default)
			)
			(layer "F.SilkS")
		)
		(fp_line
			(start -2.1844 -0.0508)
			(end -2.7178 0.508)
			(stroke
				(width 0.1524)
				(type default)
			)
			(layer "F.SilkS")
		)
		(fp_line
			(start -2.6289 3.4417)
			(end -2.6289 1.4732)
			(stroke
				(width 0.381)
				(type default)
			)
			(layer "F.SilkS")
		)
		(fp_line
			(start -2.7178 -0.508)
			(end -2.1844 -0.0508)
			(stroke
				(width 0.1524)
				(type default)
			)
			(layer "F.SilkS")
		)
		(fp_line
			(start -2.7432 1.4224)
			(end 2.1336 1.4224)
			(stroke
				(width 0.1524)
				(type default)
			)
			(layer "F.SilkS")
		)
		(fp_line
			(start -2.7432 1.4224)
			(end -2.6416 1.4224)
			(stroke
				(width 0.1524)
				(type default)
			)
			(layer "F.SilkS")
		)
		(fp_line
			(start -2.7432 -1.4224)
			(end -2.7432 1.4224)
			(stroke
				(width 0.1524)
				(type default)
			)
			(layer "F.SilkS")
		)
		(fp_poly
			(pts
				(xy -2.2098 -1.4224) (xy -2.2098 1.4224) (xy 2.2098 1.4224) (xy 2.2098 -1.4224)
			)
			(stroke
				(width 0)
				(type default)
			)
			(fill yes)
			(layer "F.SilkS")
		)
		(fp_rect
			(start -2.450084 2.999994)
			(end 2.450084 -2.999994)
			(stroke
				(width 0)
				(type default)
			)
			(fill no)
			(layer "F.CrtYd")
		)
		(fp_poly
			(pts
				(xy -2.8194 3.6322) (xy -2.8194 -3.6322) (xy 2.8194 -3.6322) (xy 2.8194 1.18364) (xy 2.450084 1.18364)
				(xy 2.450084 -2.999994) (xy -2.450084 -2.999994) (xy -2.450084 2.999994) (xy 2.450084 2.999994)
				(xy 2.450084 1.18618) (xy 2.8194 1.18618) (xy 2.8194 3.6322)
			)
			(stroke
				(width 0)
				(type default)
			)
			(fill no)
			(layer "F.CrtYd")
		)
		(fp_rect
			(start -2.8194 3.6322)
			(end 2.8194 -3.6322)
			(stroke
				(width 0)
				(type default)
			)
			(fill no)
			(layer "F.Fab")
		)
		(pad "1" smd rect
			(at -1.905 2.54 180)
			(size 0.635 1.651)
			(layers "F.Cu" "F.Mask" "F.Paste")
			(net "P5V_HDD35")
		)
		(pad "2" smd rect
			(at -0.635 2.54 180)
			(size 0.635 1.651)
			(layers "F.Cu" "F.Mask" "F.Paste")
			(net "P5V_HDD35")
		)
		(pad "3" smd rect
			(at 0.635 2.54 180)
			(size 0.635 1.651)
			(layers "F.Cu" "F.Mask" "F.Paste")
			(net "P5V_HDD35")
		)
		(pad "4" smd rect
			(at 1.905 2.54 180)
			(size 0.635 1.651)
			(layers "F.Cu" "F.Mask" "F.Paste")
			(net "SW_HDD_P35")
		)
		(pad "5" smd rect
			(at 1.905 -2.54 180)
			(size 0.635 1.651)
			(layers "F.Cu" "F.Mask" "F.Paste")
			(net "P5V_A_4")
		)
		(pad "6" smd rect
			(at 0.635 -2.54 180)
			(size 0.635 1.651)
			(layers "F.Cu" "F.Mask" "F.Paste")
			(net "P5V_A_4")
		)
		(pad "7" smd rect
			(at -0.635 -2.54 180)
			(size 0.635 1.651)
			(layers "F.Cu" "F.Mask" "F.Paste")
			(net "P5V_A_4")
		)
		(pad "8" smd rect
			(at -1.905 -2.54 180)
			(size 0.635 1.651)
			(layers "F.Cu" "F.Mask" "F.Paste")
			(net "P5V_A_4")
		)
	)
	(footprint ""
		(layer "F.Cu")
		(at 368.3508 -133.6294 90)
		(property "Reference" "R1092"
			(at 0 0 90)
			(layer "F.SilkS")
			(hide yes)
			(effects
				(font
					(size 1.27 1.27)
				)
			)
		)
		(property "Value" "100KR2F-L1-GP"
			(at 0.064008 -3.993896 90)
			(unlocked yes)
			(layer "F.Fab")
			(hide yes)
			(effects
				(font
					(size 1.016 1.016)
					(thickness 0.1524)
				)
			)
		)
		(property "Device Type" "R402H16"
			(at 0.064008 -5.517896 90)
			(unlocked yes)
			(layer "F.Fab")
			(hide yes)
			(effects
				(font
					(size 1.016 1.016)
					(thickness 0.1524)
				)
			)
		)
		(duplicate_pad_numbers_are_jumpers no)
		(fp_line
			(start 0.508 -0.9398)
			(end -0.508 -0.9398)
			(stroke
				(width 0.1524)
				(type default)
			)
			(layer "F.SilkS")
		)
		(fp_line
			(start -0.508 -0.9398)
			(end -0.508 0.9398)
			(stroke
				(width 0.1524)
				(type default)
			)
			(layer "F.SilkS")
		)
		(fp_rect
			(start -0.508 0.9398)
			(end 0.508 -0.9398)
			(stroke
				(width 0)
				(type default)
			)
			(fill no)
			(layer "F.CrtYd")
		)
		(fp_rect
			(start -0.508 0.9398)
			(end 0.508 -0.9398)
			(stroke
				(width 0)
				(type default)
			)
			(fill no)
			(layer "F.Fab")
		)
		(pad "1" smd custom
			(at 0 -0.4445 90)
			(size 0.1397 0.1397)
			(layers "F.Cu" "F.Mask" "F.Paste")
			(net "MB1_VCAP_R")
			(options
				(clearance outline)
				(anchor circle)
			)
			(primitives
				(gr_poly
					(pts
						(arc
							(start -0.1778 -0.2794)
							(mid -0.249642 -0.249642)
							(end -0.2794 -0.1778)
						)
						(arc
							(start -0.2794 0.1778)
							(mid -0.249642 0.249642)
							(end -0.1778 0.2794)
						)
						(arc
							(start 0.1778 0.2794)
							(mid 0.249642 0.249642)
							(end 0.2794 0.1778)
						)
						(arc
							(start 0.2794 -0.1778)
							(mid 0.249642 -0.249642)
							(end 0.1778 -0.2794)
						)
					)
					(width 0)
					(fill yes)
				)
			)
		)
		(pad "2" smd custom
			(at 0 0.4445 90)
			(size 0.1397 0.1397)
			(layers "F.Cu" "F.Mask" "F.Paste")
			(net "MB1_ISET_R")
			(options
				(clearance outline)
				(anchor circle)
			)
			(primitives
				(gr_poly
					(pts
						(arc
							(start -0.1778 -0.2794)
							(mid -0.249642 -0.249642)
							(end -0.2794 -0.1778)
						)
						(arc
							(start -0.2794 0.1778)
							(mid -0.249642 0.249642)
							(end -0.1778 0.2794)
						)
						(arc
							(start 0.1778 0.2794)
							(mid 0.249642 0.249642)
							(end 0.2794 0.1778)
						)
						(arc
							(start 0.2794 -0.1778)
							(mid 0.249642 -0.249642)
							(end 0.1778 -0.2794)
						)
					)
					(width 0)
					(fill yes)
				)
			)
		)
	)
	(footprint ""
		(layer "F.Cu")
		(at 222.631 -119.6594 -90)
		(property "Reference" "R618"
			(at 0 0 270)
			(layer "F.SilkS")
			(hide yes)
			(effects
				(font
					(size 1.27 1.27)
				)
			)
		)
		(property "Value" "4K7R2F-GP"
			(at 0.064008 -3.993896 270)
			(unlocked yes)
			(layer "F.Fab")
			(hide yes)
			(effects
				(font
					(size 1.016 1.016)
					(thickness 0.1524)
				)
			)
		)
		(property "Device Type" "R402H16"
			(at 0.064008 -5.517896 270)
			(unlocked yes)
			(layer "F.Fab")
			(hide yes)
			(effects
				(font
					(size 1.016 1.016)
					(thickness 0.1524)
				)
			)
		)
		(duplicate_pad_numbers_are_jumpers no)
		(fp_line
			(start -0.508 -0.9398)
			(end -0.508 0.9398)
			(stroke
				(width 0.1524)
				(type default)
			)
			(layer "F.SilkS")
		)
		(fp_line
			(start 0.508 -0.9398)
			(end -0.508 -0.9398)
			(stroke
				(width 0.1524)
				(type default)
			)
			(layer "F.SilkS")
		)
		(fp_rect
			(start -0.508 0.9398)
			(end 0.508 -0.9398)
			(stroke
				(width 0)
				(type default)
			)
			(fill no)
			(layer "F.CrtYd")
		)
		(fp_rect
			(start -0.508 0.9398)
			(end 0.508 -0.9398)
			(stroke
				(width 0)
				(type default)
			)
			(fill no)
			(layer "F.Fab")
		)
		(pad "1" smd custom
			(at 0 -0.4445 270)
			(size 0.1397 0.1397)
			(layers "F.Cu" "F.Mask" "F.Paste")
			(net "COMP_A_BMC_A_ALERT_N")
			(options
				(clearance outline)
				(anchor circle)
			)
			(primitives
				(gr_poly
					(pts
						(arc
							(start -0.1778 -0.2794)
							(mid -0.249642 -0.249642)
							(end -0.2794 -0.1778)
						)
						(arc
							(start -0.2794 0.1778)
							(mid -0.249642 0.249642)
							(end -0.1778 0.2794)
						)
						(arc
							(start 0.1778 0.2794)
							(mid 0.249642 0.249642)
							(end 0.2794 0.1778)
						)
						(arc
							(start 0.2794 -0.1778)
							(mid 0.249642 -0.249642)
							(end 0.1778 -0.2794)
						)
					)
					(width 0)
					(fill yes)
				)
			)
		)
		(pad "2" smd custom
			(at 0 0.4445 270)
			(size 0.1397 0.1397)
			(layers "F.Cu" "F.Mask" "F.Paste")
			(net "P3V3_STBY_A")
			(options
				(clearance outline)
				(anchor circle)
			)
			(primitives
				(gr_poly
					(pts
						(arc
							(start -0.1778 -0.2794)
							(mid -0.249642 -0.249642)
							(end -0.2794 -0.1778)
						)
						(arc
							(start -0.2794 0.1778)
							(mid -0.249642 0.249642)
							(end -0.1778 0.2794)
						)
						(arc
							(start 0.1778 0.2794)
							(mid 0.249642 0.249642)
							(end 0.2794 0.1778)
						)
						(arc
							(start 0.2794 -0.1778)
							(mid 0.249642 -0.249642)
							(end 0.1778 -0.2794)
						)
					)
					(width 0)
					(fill yes)
				)
			)
		)
	)
)
